FILE_TYPE = CONNECTIVITY;
{Allegro Design Entry HDL 17.2-2016 S081 (4005846) 1/11/2022}
"PAGE_NUMBER" = 125;
0"NC";
1"PVNN_TERM_CPU1\g";
2"PVCCD_HV_CPU1\g";
3"PVCCD_HV_CPU1\g";
4"PVCCD_HV_CPU1\g";
5"PVNN_TERM_CPU1\g";
6"PVCCD_HV_CPU1\g";
7"PWRGD_CPU1_LVC1";
8"PWRGD_DRAMPWRGD_CPU1_GH_LVC1_R";
9"PWRGD_DRAMPWRGD_CPU1_EF_LVC1_R2";
10"PWRGD_DRAMPWRGD_CPU1_CD_LVC1_R";
11"PWRGD_DRAMPWRGD_CPU1_GH_LVC1_R2";
12"PWRGD_DRAMPWRGD_CPU1_EF_LVC1_R";
13"PWRGD_DRAMPWRGD_CPU1_AB_LVC1_R";
14"PWRGD_DRAMPWRGD_CPU1_AB_LVC1_R2";
15"PWRGD_DRAMPWRGD_CPU1_CD_LVC1_R2";
16"PWRGD_CPU1_BUF_R";
17"PWRGD_DRAMPWRGD_CPU1_EF_R_LVC1";
18"RST_CPU1_LVC1_N";
19"RST_CPU1_BUF_R_N";
20"PWRGD_CPU1_LVC1_R";
21"PWRGD_DRAMPWRGD_CPU1_CD_R_LVC1";
22"RST_CPU1_LVC1_R_N";
23"PWRGD_DRAMPWRGD_CPU1_GH_R_LVC1";
24"PWRGD_DRAMPWRGD_CPU1_AB_R_LVC1";
%"Q_RES"
"1","(-5300,1600)","0","pure_quanta","I13";
;
PART_NUMBER"CS00002JB13"
MATERIAL"CHIP"
TOLERANCE"5%"
VALUE"0"
PACK_TYPE"0402LF"
WATTAGE"1/16W"
$LOCATION"R126"
CDS_LIB"pure_quanta"
CDS_LOCATION"R126"
$SEC"1"
CDS_SEC"1";
"B"
$PN"2"9;
"A"
$PN"1"17;
%"Q_RES"
"1","(-5300,2450)","0","pure_quanta","I15";
;
PART_NUMBER"CS00002JB13"
PACK_TYPE"0402LF"
MATERIAL"CHIP"
WATTAGE"1/16W"
TOLERANCE"5%"
VALUE"0"
$LOCATION"R124"
CDS_LIB"pure_quanta"
CDS_LOCATION"R124"
$SEC"1"
CDS_SEC"1";
"B"
$PN"2"15;
"A"
$PN"1"21;
%"Q_RES"
"1","(-5300,3275)","0","pure_quanta","I17";
;
PART_NUMBER"CS00002JB13"
WATTAGE"1/16W"
VALUE"0"
TOLERANCE"5%"
PACK_TYPE"0402LF"
MATERIAL"CHIP"
$LOCATION"R122"
CDS_LIB"pure_quanta"
CDS_LOCATION"R122"
$SEC"1"
CDS_SEC"1";
"B"
$PN"2"14;
"A"
$PN"1"24;
%"Q_RES"
"1","(-1125,-725)","0","pure_quanta","I24";
;
PART_NUMBER"CS11002FB07"
VALUE"100"
WATTAGE"1/16W"
PACK_TYPE"0402LF"
MATERIAL"CHIP"
TOLERANCE"1%"
$LOCATION"R157"
CDS_LIB"pure_quanta"
CDS_LOCATION"R157"
$SEC"1"
CDS_SEC"1";
"B"
$PN"2"5;
"A"
$PN"1"19;
%"Q_RES"
"1","(-1125,125)","0","pure_quanta","I26";
;
PART_NUMBER"CS11002FB07"
PACK_TYPE"0402LF"
MATERIAL"CHIP"
WATTAGE"1/16W"
VALUE"100"
TOLERANCE"1%"
$LOCATION"R155"
CDS_LIB"pure_quanta"
CDS_LOCATION"R155"
$SEC"1"
CDS_SEC"1";
"B"
$PN"2"1;
"A"
$PN"1"16;
%"UNIVERSAL_POWER"
"1","(-525,-625)","0","logical_power","I27";
;
HDL_POWER"PVNN_TERM_CPU1"
CDS_LIB"logical_power";
"A"5;
%"UNIVERSAL_POWER"
"1","(-525,225)","0","logical_power","I29";
;
HDL_POWER"PVNN_TERM_CPU1"
CDS_LIB"logical_power";
"A"1;
%"Q_RES"
"1","(-5300,-900)","0","pure_quanta","I3";
;
PART_NUMBER"CS00002JB13"
MATERIAL"CHIP"
VALUE"0"
TOLERANCE"5%"
PACK_TYPE"0402LF"
WATTAGE"1/16W"
$LOCATION"R132"
CDS_LIB"pure_quanta"
CDS_LOCATION"R132"
$SEC"1"
CDS_SEC"1";
"B"
$PN"2"19;
"A"
$PN"1"22;
%"Q_RES"
"1","(-5300,-50)","0","pure_quanta","I5";
;
PART_NUMBER"CS00002JB13"
MATERIAL"CHIP"
WATTAGE"1/16W"
VALUE"0"
TOLERANCE"5%"
PACK_TYPE"0402LF"
$LOCATION"R130"
CDS_LIB"pure_quanta"
CDS_LOCATION"R130"
$SEC"1"
CDS_SEC"1";
"B"
$PN"2"16;
"A"
$PN"1"20;
%"Q_RES"
"1","(-1100,950)","0","pure_quanta","I56";
;
PART_NUMBER"CS11002FB07"
MATERIAL"CHIP"
PACK_TYPE"0402LF"
VALUE"100"
WATTAGE"1/16W"
TOLERANCE"1%"
$LOCATION"R153"
CDS_LIB"pure_quanta"
CDS_LOCATION"R153"
$SEC"1"
CDS_SEC"1";
"B"
$PN"2"2;
"A"
$PN"1"11;
%"UNIVERSAL_POWER"
"1","(-500,1050)","0","logical_power","I57";
;
HDL_POWER"PVCCD_HV_CPU1"
CDS_LIB"logical_power";
"A"2;
%"Q_RES"
"1","(-1100,1775)","0","pure_quanta","I58";
;
PART_NUMBER"CS11002FB07"
MATERIAL"CHIP"
VALUE"100"
PACK_TYPE"0402LF"
WATTAGE"1/16W"
TOLERANCE"1%"
$LOCATION"R151"
CDS_LIB"pure_quanta"
CDS_LOCATION"R151"
$SEC"1"
CDS_SEC"1";
"B"
$PN"2"6;
"A"
$PN"1"9;
%"UNIVERSAL_POWER"
"1","(-500,1875)","0","logical_power","I59";
;
HDL_POWER"PVCCD_HV_CPU1"
CDS_LIB"logical_power";
"A"6;
%"Q_RES"
"1","(-1100,2625)","0","pure_quanta","I60";
;
PART_NUMBER"CS11002FB07"
MATERIAL"CHIP"
TOLERANCE"1%"
PACK_TYPE"0402LF"
WATTAGE"1/16W"
VALUE"100"
$LOCATION"R137"
CDS_LIB"pure_quanta"
CDS_LOCATION"R137"
$SEC"1"
CDS_SEC"1";
"B"
$PN"2"3;
"A"
$PN"1"15;
%"UNIVERSAL_POWER"
"1","(-500,2725)","0","logical_power","I61";
;
HDL_POWER"PVCCD_HV_CPU1"
CDS_LIB"logical_power";
"A"3;
%"Q_RES"
"1","(-1100,3450)","0","pure_quanta","I62";
;
PART_NUMBER"CS11002FB07"
MATERIAL"CHIP"
TOLERANCE"1%"
WATTAGE"1/16W"
VALUE"100"
PACK_TYPE"0402LF"
$LOCATION"R135"
CDS_LIB"pure_quanta"
CDS_LOCATION"R135"
$SEC"1"
CDS_SEC"1";
"B"
$PN"2"4;
"A"
$PN"1"14;
%"UNIVERSAL_POWER"
"1","(-500,3550)","0","logical_power","I63";
;
HDL_POWER"PVCCD_HV_CPU1"
CDS_LIB"logical_power";
"A"4;
%"Q_RES"
"1","(-1125,-50)","0","pure_quanta","I64";
;
PART_NUMBER"CS11002FB07"
TOLERANCE"1%"
PACK_TYPE"0402LF"
VALUE"100"
WATTAGE"1/16W"
MATERIAL"CHIP"
LOCATION"R156"
CDS_LIB"pure_quanta"
$SEC"1"
CDS_SEC"1";
"B"
$PN"2"7;
"A"
$PN"1"16;
%"Q_RES"
"1","(-1125,-900)","0","pure_quanta","I65";
;
PART_NUMBER"CS11002FB07"
MATERIAL"CHIP"
WATTAGE"1/16W"
TOLERANCE"1%"
PACK_TYPE"0402LF"
VALUE"100"
LOCATION"R158"
CDS_LIB"pure_quanta"
$SEC"1"
CDS_SEC"1";
"B"
$PN"2"18;
"A"
$PN"1"19;
%"Q_RES"
"1","(-1100,775)","0","pure_quanta","I66";
;
PART_NUMBER"CS11002FB07"
PACK_TYPE"0402LF"
MATERIAL"CHIP"
TOLERANCE"1%"
WATTAGE"1/16W"
VALUE"100"
$LOCATION"R4302"
CDS_LIB"pure_quanta"
CDS_LOCATION"R4302"
$SEC"1"
CDS_SEC"1";
"B"
$PN"2"8;
"A"
$PN"1"11;
%"Q_RES"
"1","(-1100,1600)","0","pure_quanta","I68";
;
PART_NUMBER"CS11002FB07"
VALUE"100"
PACK_TYPE"0402LF"
TOLERANCE"1%"
WATTAGE"1/16W"
MATERIAL"CHIP"
$LOCATION"R4301"
CDS_LIB"pure_quanta"
CDS_LOCATION"R4301"
$SEC"1"
CDS_SEC"1";
"B"
$PN"2"12;
"A"
$PN"1"9;
%"Q_RES"
"1","(-5300,775)","0","pure_quanta","I7";
;
PART_NUMBER"CS00002JB13"
VALUE"0"
TOLERANCE"5%"
MATERIAL"CHIP"
WATTAGE"1/16W"
PACK_TYPE"0402LF"
$LOCATION"R128"
CDS_LIB"pure_quanta"
CDS_LOCATION"R128"
$SEC"1"
CDS_SEC"1";
"B"
$PN"2"11;
"A"
$PN"1"23;
%"Q_RES"
"1","(-1100,2450)","0","pure_quanta","I70";
;
PART_NUMBER"CS11002FB07"
VALUE"100"
PACK_TYPE"0402LF"
WATTAGE"1/16W"
TOLERANCE"1%"
MATERIAL"CHIP"
$LOCATION"R4300"
CDS_LIB"pure_quanta"
CDS_LOCATION"R4300"
$SEC"1"
CDS_SEC"1";
"B"
$PN"2"10;
"A"
$PN"1"15;
%"Q_RES"
"1","(-1100,3300)","0","pure_quanta","I72";
;
PART_NUMBER"CS11002FB07"
VALUE"100"
PACK_TYPE"0402LF"
MATERIAL"CHIP"
WATTAGE"1/16W"
TOLERANCE"1%"
$LOCATION"R4299"
CDS_LIB"pure_quanta"
CDS_LOCATION"R4299"
$SEC"1"
CDS_SEC"1";
"B"
$PN"2"13;
"A"
$PN"1"14;
END.
